G04*
G04 #@! TF.GenerationSoftware,Altium Limited,Altium Designer,23.7.1 (13)*
G04*
G04 Layer_Color=128*
%FSLAX25Y25*%
%MOIN*%
G70*
G04*
G04 #@! TF.SameCoordinates,AF00DCEB-AC48-4C7C-91EA-99F42E284231*
G04*
G04*
G04 #@! TF.FilePolarity,Positive*
G04*
G01*
G75*
%ADD42R,0.01772X0.01772*%
%ADD43R,0.04331X0.04134*%
%ADD46R,0.04134X0.04331*%
%ADD52R,0.01457X0.00945*%
%ADD53R,0.01575X0.04252*%
%ADD60R,0.01968X0.01772*%
%ADD64R,0.02165X0.02165*%
%ADD68R,0.01772X0.01968*%
%ADD69R,0.02165X0.02165*%
%ADD86R,0.02816X0.02648*%
%ADD87R,0.02016X0.02288*%
%ADD88R,0.02911X0.02648*%
%ADD89R,0.02756X0.02756*%
%ADD106R,0.02559X0.02362*%
%ADD113R,0.02648X0.02911*%
%ADD119R,0.02362X0.02559*%
%ADD120R,0.02288X0.02016*%
%ADD124R,0.02648X0.02816*%
%ADD141R,0.02800X0.16500*%
%ADD142R,0.02800X0.12600*%
G04:AMPARAMS|DCode=253|XSize=25.98mil|YSize=12.6mil|CornerRadius=1.58mil|HoleSize=0mil|Usage=FLASHONLY|Rotation=0.000|XOffset=0mil|YOffset=0mil|HoleType=Round|Shape=RoundedRectangle|*
%AMROUNDEDRECTD253*
21,1,0.02598,0.00945,0,0,0.0*
21,1,0.02284,0.01260,0,0,0.0*
1,1,0.00315,0.01142,-0.00472*
1,1,0.00315,-0.01142,-0.00472*
1,1,0.00315,-0.01142,0.00472*
1,1,0.00315,0.01142,0.00472*
%
%ADD253ROUNDEDRECTD253*%
%ADD254R,0.02559X0.02559*%
%ADD255R,0.02559X0.02559*%
%ADD256R,0.02559X0.02756*%
%ADD257R,0.02835X0.03937*%
%ADD258R,0.02165X0.01968*%
%ADD259R,0.01968X0.02362*%
%ADD260R,0.02712X0.02648*%
%ADD261R,0.02953X0.02756*%
%ADD262R,0.02362X0.01968*%
%ADD263R,0.01772X0.01772*%
%ADD264R,0.03347X0.02953*%
%ADD265R,0.03150X0.03740*%
%ADD266R,0.03937X0.04921*%
%ADD267R,0.04921X0.03937*%
%ADD268R,0.02029X0.01860*%
%ADD269R,0.02205X0.02047*%
%ADD270R,0.02520X0.02677*%
%ADD271R,0.02756X0.02756*%
%ADD272R,0.02677X0.02520*%
%ADD273R,0.02362X0.03150*%
D42*
X109055Y-30315D02*
D03*
X112205D02*
D03*
X160863Y-121457D02*
D03*
X157713D02*
D03*
X425197Y-105512D02*
D03*
X422047D02*
D03*
X92732Y-13129D02*
D03*
X89583D02*
D03*
X43268Y-48355D02*
D03*
X46417D02*
D03*
X43268Y-43355D02*
D03*
X46417D02*
D03*
X158107Y-137205D02*
D03*
X154957D02*
D03*
X162437Y-136417D02*
D03*
X165587D02*
D03*
X43701Y-148819D02*
D03*
X46850D02*
D03*
X161596Y-117597D02*
D03*
X164746D02*
D03*
X156434Y-132185D02*
D03*
X159583D02*
D03*
X160863Y-125000D02*
D03*
X157713D02*
D03*
X160469Y-128937D02*
D03*
X157319D02*
D03*
D43*
X425938Y-194488D02*
D03*
Y-200000D02*
D03*
X162992Y-42913D02*
D03*
Y-48425D02*
D03*
D46*
X555512Y-340158D02*
D03*
X561024D02*
D03*
X535827Y-338976D02*
D03*
X530315D02*
D03*
X568898Y-319291D02*
D03*
X563386D02*
D03*
X536221Y-300787D02*
D03*
X530709D02*
D03*
X128159Y-65403D02*
D03*
X122648D02*
D03*
X117825Y-47401D02*
D03*
X123337D02*
D03*
X149606Y-80315D02*
D03*
X144095D02*
D03*
X222835Y-138189D02*
D03*
X217323D02*
D03*
X198031Y-111811D02*
D03*
X192520D02*
D03*
D52*
X587625Y-281567D02*
D03*
Y-279992D02*
D03*
Y-278418D02*
D03*
X591680D02*
D03*
Y-279992D02*
D03*
Y-281567D02*
D03*
D53*
X589652Y-279992D02*
D03*
D60*
X43925Y-154365D02*
D03*
X46878D02*
D03*
X585335Y-214173D02*
D03*
X582382D02*
D03*
X586909Y-196850D02*
D03*
X583957D02*
D03*
X582382Y-206693D02*
D03*
X585335D02*
D03*
D64*
X590748Y-185827D02*
D03*
X587205D02*
D03*
D68*
X589764Y-178642D02*
D03*
Y-175689D02*
D03*
X589730Y-158745D02*
D03*
Y-161698D02*
D03*
D69*
X581890Y-243602D02*
D03*
Y-240059D02*
D03*
X590158Y-224311D02*
D03*
Y-227854D02*
D03*
X584646Y-228937D02*
D03*
Y-232480D02*
D03*
D86*
X97553Y-77165D02*
D03*
X93785D02*
D03*
D87*
X544471Y-273290D02*
D03*
Y-270412D02*
D03*
X580866Y-278931D02*
D03*
Y-276053D02*
D03*
X596220Y-279718D02*
D03*
Y-276840D02*
D03*
X477872Y-298948D02*
D03*
Y-301826D02*
D03*
X189764Y-95927D02*
D03*
Y-93049D02*
D03*
X151751Y2505D02*
D03*
Y5383D02*
D03*
X209449Y4195D02*
D03*
Y1317D02*
D03*
X203839Y-1514D02*
D03*
Y-4392D02*
D03*
X214173Y-1711D02*
D03*
Y-4589D02*
D03*
X204537Y-76439D02*
D03*
Y-73561D02*
D03*
X214173Y-76242D02*
D03*
Y-73364D02*
D03*
X108661Y-47638D02*
D03*
Y-44760D02*
D03*
X281890Y-196715D02*
D03*
Y-193836D02*
D03*
X158661Y-101429D02*
D03*
Y-98551D02*
D03*
D88*
X413911Y-124409D02*
D03*
X417585D02*
D03*
X114829Y-16142D02*
D03*
X111155D02*
D03*
D89*
X64528Y-58729D02*
D03*
Y-53218D02*
D03*
X101969Y-49213D02*
D03*
Y-43701D02*
D03*
X164961Y-98819D02*
D03*
Y-104331D02*
D03*
D106*
X442028Y-154331D02*
D03*
X445374D02*
D03*
X71752Y787D02*
D03*
X68405D02*
D03*
X53248Y-5709D02*
D03*
X56595D02*
D03*
X536434Y-256004D02*
D03*
X533088D02*
D03*
X535257Y-250886D02*
D03*
X531910D02*
D03*
X533249Y-245374D02*
D03*
X529902D02*
D03*
X414725Y-104643D02*
D03*
X418071D02*
D03*
X52854Y394D02*
D03*
X49508D02*
D03*
X64862Y-5709D02*
D03*
X61516D02*
D03*
X92831Y-16929D02*
D03*
X89484D02*
D03*
X23524Y-294882D02*
D03*
X26870D02*
D03*
D113*
X96063Y-48687D02*
D03*
Y-45013D02*
D03*
X153150Y-99738D02*
D03*
Y-103412D02*
D03*
D119*
X437303Y-144390D02*
D03*
Y-147736D02*
D03*
X441732Y-144390D02*
D03*
Y-147736D02*
D03*
X452854Y-144390D02*
D03*
Y-147736D02*
D03*
X210236Y-40431D02*
D03*
Y-37085D02*
D03*
X215354Y-38291D02*
D03*
Y-34944D02*
D03*
X220866Y-35972D02*
D03*
Y-32626D02*
D03*
X18110Y-296161D02*
D03*
Y-292815D02*
D03*
X8661Y-193012D02*
D03*
Y-189665D02*
D03*
D120*
X558375Y-280755D02*
D03*
X555497D02*
D03*
X478876Y-265748D02*
D03*
X481754D02*
D03*
X495805Y-252362D02*
D03*
X498683D02*
D03*
X509116Y-260136D02*
D03*
X506238D02*
D03*
X496199Y-259842D02*
D03*
X499077D02*
D03*
X564506Y-261119D02*
D03*
X567384D02*
D03*
X574766Y-261122D02*
D03*
X571888D02*
D03*
X340809Y-292913D02*
D03*
X337931D02*
D03*
X321912Y-293701D02*
D03*
X319033D02*
D03*
X327030Y-239764D02*
D03*
X324151D02*
D03*
X376514Y-232972D02*
D03*
X379392D02*
D03*
X611553Y-238583D02*
D03*
X614431D02*
D03*
X612887Y-231102D02*
D03*
X615765D02*
D03*
D124*
X596220Y-283876D02*
D03*
Y-287644D02*
D03*
X580866Y-283482D02*
D03*
Y-287250D02*
D03*
D141*
X281102Y-401427D02*
D03*
X159055D02*
D03*
X155118D02*
D03*
X186614D02*
D03*
X182677D02*
D03*
X241732D02*
D03*
X273228D02*
D03*
X269291D02*
D03*
X257480D02*
D03*
X237795D02*
D03*
X253543D02*
D03*
X222047D02*
D03*
X218110D02*
D03*
X210236D02*
D03*
X206299D02*
D03*
X190551D02*
D03*
X166929D02*
D03*
X170866D02*
D03*
X174803D02*
D03*
X178740D02*
D03*
X229921D02*
D03*
X214173D02*
D03*
X202362D02*
D03*
X249606D02*
D03*
X265354D02*
D03*
X245669D02*
D03*
X277165D02*
D03*
X261417D02*
D03*
X233858D02*
D03*
X225984D02*
D03*
X162992D02*
D03*
D142*
X151181Y-399477D02*
D03*
D253*
X564889Y-280519D02*
D03*
Y-282487D02*
D03*
Y-278550D02*
D03*
Y-276582D02*
D03*
X570676D02*
D03*
Y-278550D02*
D03*
Y-280519D02*
D03*
Y-282487D02*
D03*
X536772Y-273701D02*
D03*
Y-271732D02*
D03*
Y-275669D02*
D03*
Y-277638D02*
D03*
X530984D02*
D03*
Y-275669D02*
D03*
Y-273701D02*
D03*
Y-271732D02*
D03*
D254*
X532266Y-282481D02*
D03*
X536203D02*
D03*
X568963Y-272841D02*
D03*
X565026D02*
D03*
X558727Y-275597D02*
D03*
X554790D02*
D03*
D255*
X542126Y-277953D02*
D03*
Y-281890D02*
D03*
D256*
X111024Y-21752D02*
D03*
Y-25492D02*
D03*
D257*
X287835Y-273622D02*
D03*
X293268D02*
D03*
D258*
X400984Y-129921D02*
D03*
X403937D02*
D03*
D259*
X412205Y-129528D02*
D03*
X408268D02*
D03*
D260*
X431943Y-132677D02*
D03*
X427900D02*
D03*
D261*
X423917Y-137992D02*
D03*
X427658D02*
D03*
X56595Y-27362D02*
D03*
X60335D02*
D03*
D262*
X56824Y-31594D02*
D03*
Y-35531D02*
D03*
D263*
X378083Y-153937D02*
D03*
Y-157087D02*
D03*
X373083Y-153937D02*
D03*
Y-157087D02*
D03*
X603357Y-83008D02*
D03*
Y-79858D02*
D03*
X598425Y-83071D02*
D03*
Y-79921D02*
D03*
X158008Y-118602D02*
D03*
Y-115453D02*
D03*
X164012Y-128150D02*
D03*
Y-131299D02*
D03*
D264*
X432237Y-199705D02*
D03*
Y-204232D02*
D03*
D265*
X26083Y16339D02*
D03*
X31398D02*
D03*
X26083Y9449D02*
D03*
X31398D02*
D03*
X26083Y2559D02*
D03*
X31398D02*
D03*
X26083Y-4331D02*
D03*
X31398D02*
D03*
X199114Y-130709D02*
D03*
X204035D02*
D03*
D266*
X561024Y-330315D02*
D03*
X553150D02*
D03*
X529282Y-328837D02*
D03*
X537156D02*
D03*
X562205Y-309842D02*
D03*
X570079D02*
D03*
X529282Y-312272D02*
D03*
X537156D02*
D03*
X125984Y-36220D02*
D03*
X118110D02*
D03*
X121467Y-74575D02*
D03*
X129341D02*
D03*
X144096Y-71072D02*
D03*
X151970D02*
D03*
D267*
X148632Y-49655D02*
D03*
Y-41781D02*
D03*
D268*
X612781Y-302756D02*
D03*
X615762D02*
D03*
X152904Y-124213D02*
D03*
X149924D02*
D03*
D269*
X604252Y-242991D02*
D03*
X601181D02*
D03*
X604252Y-239054D02*
D03*
X601181D02*
D03*
D270*
X172939Y-124276D02*
D03*
Y-120812D02*
D03*
X59016Y-54241D02*
D03*
Y-57706D02*
D03*
X168441Y-115295D02*
D03*
Y-118760D02*
D03*
X273441Y-382293D02*
D03*
Y-378907D02*
D03*
X206441D02*
D03*
Y-382293D02*
D03*
X210441D02*
D03*
Y-378907D02*
D03*
X218341D02*
D03*
Y-382293D02*
D03*
X222641D02*
D03*
Y-378907D02*
D03*
X237941Y-382293D02*
D03*
Y-378907D02*
D03*
X241941Y-382293D02*
D03*
Y-378907D02*
D03*
X253441Y-382293D02*
D03*
Y-378907D02*
D03*
X256941D02*
D03*
Y-382293D02*
D03*
X269441D02*
D03*
Y-378907D02*
D03*
D271*
X388713Y-135039D02*
D03*
X383201D02*
D03*
X613779Y-64961D02*
D03*
X608268D02*
D03*
D272*
X609291Y-59842D02*
D03*
X612756D02*
D03*
X384532Y-141339D02*
D03*
X387996D02*
D03*
D273*
X228150Y-132677D02*
D03*
X223031D02*
D03*
X238386Y-131890D02*
D03*
X233268D02*
D03*
M02*
